(kicad_pcb
	(version 20260206)
	(generator "pcbnew")
	(generator_version "10.0")
	(general
		(thickness 1.6)
		(legacy_teardrops no)
	)
	(paper "A4")
	(title_block
		(title "Bryce Canyon_R.DPB_16317-1_OCP.brd")
		(comment 1 "Bryce Canyon / footprints 344-350 of 2099")
	)
	(layers
		(0 "F.Cu" signal "TOP")
		(4 "In1.Cu" signal "L2GND")
		(6 "In2.Cu" signal "L3")
		(8 "In3.Cu" signal "L4VCC")
		(10 "In4.Cu" signal "L5VCC")
		(12 "In5.Cu" signal "L6")
		(14 "In6.Cu" signal "L7GND")
		(2 "B.Cu" signal "BOTTOM")
		(9 "F.Adhes" user "F.Adhesive")
		(11 "B.Adhes" user "B.Adhesive")
		(13 "F.Paste" user "Package Geometry/Pastemask Top")
		(15 "B.Paste" user "Package Geometry/Pastemask Bottom")
		(5 "F.SilkS" user "Ref Des/Silkscreen Top")
		(7 "B.SilkS" user "Ref Des/Silkscreen Bottom")
		(1 "F.Mask" user "Board Geometry/Soldermask Top")
		(3 "B.Mask" user "Board Geometry/Soldermask Bottom")
		(17 "Dwgs.User" user "User.Drawings")
		(19 "Cmts.User" user "User.Comments")
		(21 "Eco1.User" user "User.Eco1")
		(23 "Eco2.User" user "User.Eco2")
		(25 "Edge.Cuts" user "Board Geometry/Outline")
		(27 "Margin" user)
		(31 "F.CrtYd" user "Package Geometry/Place Bound Top")
		(29 "B.CrtYd" user "Package Geometry/Place Bound Bottom")
		(35 "F.Fab" user "Ref Des/Assembly Top")
		(33 "B.Fab" user "Ref Des/Assembly Bottom")
	)
	(footprint ""
		(layer "F.Cu")
		(at 256.921 -215.011 -90)
		(property "Reference" "C25"
			(at 0 0 270)
			(layer "F.SilkS")
			(hide yes)
			(effects
				(font
					(size 1.27 1.27)
				)
			)
		)
		(property "Value" "SCD1U16V2KX-3GP"
			(at 1.1811 -2.7051 270)
			(unlocked yes)
			(layer "F.Fab")
			(hide yes)
			(effects
				(font
					(size 1.016 1.016)
					(thickness 0.1524)
				)
			)
		)
		(property "Device Type" "C402H22"
			(at 1.1811 -4.2291 270)
			(unlocked yes)
			(layer "F.Fab")
			(hide yes)
			(effects
				(font
					(size 1.016 1.016)
					(thickness 0.1524)
				)
			)
		)
		(duplicate_pad_numbers_are_jumpers no)
		(fp_rect
			(start -0.4318 0.9525)
			(end 0.4318 -0.9525)
			(stroke
				(width 0)
				(type default)
			)
			(fill no)
			(layer "F.CrtYd")
		)
		(fp_rect
			(start -0.4318 0.9525)
			(end 0.4318 -0.9525)
			(stroke
				(width 0)
				(type default)
			)
			(fill no)
			(layer "F.Fab")
		)
		(pad "1" smd custom
			(at 0 -0.4445 270)
			(size 0.1524 0.1524)
			(layers "F.Cu" "F.Mask" "F.Paste")
			(net "P3V3_STBY_B")
			(options
				(clearance outline)
				(anchor circle)
			)
			(primitives
				(gr_poly
					(pts
						(arc
							(start 0.3048 -0.2032)
							(mid 0.275042 -0.275042)
							(end 0.2032 -0.3048)
						)
						(arc
							(start -0.2032 -0.3048)
							(mid -0.275042 -0.275042)
							(end -0.3048 -0.2032)
						)
						(arc
							(start -0.3048 0.2032)
							(mid -0.275042 0.275042)
							(end -0.2032 0.3048)
						)
						(arc
							(start 0.2032 0.3048)
							(mid 0.275042 0.275042)
							(end 0.3048 0.2032)
						)
					)
					(width 0)
					(fill yes)
				)
			)
		)
		(pad "2" smd custom
			(at 0 0.4445 270)
			(size 0.1524 0.1524)
			(layers "F.Cu" "F.Mask" "F.Paste")
			(net "GND")
			(options
				(clearance outline)
				(anchor circle)
			)
			(primitives
				(gr_poly
					(pts
						(arc
							(start 0.3048 -0.2032)
							(mid 0.275042 -0.275042)
							(end 0.2032 -0.3048)
						)
						(arc
							(start -0.2032 -0.3048)
							(mid -0.275042 -0.275042)
							(end -0.3048 -0.2032)
						)
						(arc
							(start -0.3048 0.2032)
							(mid -0.275042 0.275042)
							(end -0.2032 0.3048)
						)
						(arc
							(start 0.2032 0.3048)
							(mid 0.275042 0.275042)
							(end 0.3048 0.2032)
						)
					)
					(width 0)
					(fill yes)
				)
			)
		)
	)
	(footprint ""
		(layer "F.Cu")
		(at 259.272278 -236.1565 -90)
		(property "Reference" "Q25"
			(at 0 0 270)
			(layer "F.SilkS")
			(hide yes)
			(effects
				(font
					(size 1.27 1.27)
				)
			)
		)
		(property "Value" "2N7002K-1-GP"
			(at 0.127 -8.9662 270)
			(unlocked yes)
			(layer "F.Fab")
			(hide yes)
			(effects
				(font
					(size 1.016 1.016)
					(thickness 0.1524)
				)
			)
		)
		(property "Device Type" "SOT23DGS2D4H44"
			(at 0.127 -10.4902 270)
			(unlocked yes)
			(layer "F.Fab")
			(hide yes)
			(effects
				(font
					(size 1.016 1.016)
					(thickness 0.1524)
				)
			)
		)
		(duplicate_pad_numbers_are_jumpers no)
		(fp_line
			(start -1.651 1.778)
			(end 1.651 1.778)
			(stroke
				(width 0.1524)
				(type default)
			)
			(layer "F.SilkS")
		)
		(fp_line
			(start 1.651 1.778)
			(end 1.651 -1.778)
			(stroke
				(width 0.1524)
				(type default)
			)
			(layer "F.SilkS")
		)
		(fp_line
			(start -1.651 -1.778)
			(end -1.651 1.778)
			(stroke
				(width 0.1524)
				(type default)
			)
			(layer "F.SilkS")
		)
		(fp_line
			(start 1.651 -1.778)
			(end -1.651 -1.778)
			(stroke
				(width 0.1524)
				(type default)
			)
			(layer "F.SilkS")
		)
		(fp_poly
			(pts
				(xy -1.778 1.8796) (xy -1.778 -1.8796) (xy 1.778 -1.8796) (xy 1.778 1.8796)
			)
			(stroke
				(width 0)
				(type default)
			)
			(fill no)
			(layer "F.CrtYd")
		)
		(fp_poly
			(pts
				(xy -1.778 1.8796) (xy -1.778 -1.8796) (xy 1.778 -1.8796) (xy 1.778 1.8796)
			)
			(stroke
				(width 0)
				(type default)
			)
			(fill no)
			(layer "F.Fab")
		)
		(pad "D" smd custom
			(at 0 -0.9525 270)
			(size 0.1905 0.1905)
			(layers "F.Cu" "F.Mask" "F.Paste")
			(net "SCC_B_FULL_PWR_EN_12V")
			(options
				(clearance outline)
				(anchor circle)
			)
			(primitives
				(gr_poly
					(pts
						(arc
							(start -0.1778 0.5715)
							(mid -0.321484 0.511984)
							(end -0.381 0.3683)
						)
						(arc
							(start -0.381 -0.3683)
							(mid -0.321484 -0.511984)
							(end -0.1778 -0.5715)
						)
						(arc
							(start 0.1778 -0.5715)
							(mid 0.321484 -0.511984)
							(end 0.381 -0.3683)
						)
						(arc
							(start 0.381 0.3683)
							(mid 0.321484 0.511984)
							(end 0.1778 0.5715)
						)
					)
					(width 0)
					(fill yes)
				)
			)
		)
		(pad "G" smd custom
			(at -0.98425 0.9525 270)
			(size 0.1905 0.1905)
			(layers "F.Cu" "F.Mask" "F.Paste")
			(net "SCC_B_FULL_PWR_EN")
			(options
				(clearance outline)
				(anchor circle)
			)
			(primitives
				(gr_poly
					(pts
						(arc
							(start -0.1778 0.5715)
							(mid -0.321484 0.511984)
							(end -0.381 0.3683)
						)
						(arc
							(start -0.381 -0.3683)
							(mid -0.321484 -0.511984)
							(end -0.1778 -0.5715)
						)
						(arc
							(start 0.1778 -0.5715)
							(mid 0.321484 -0.511984)
							(end 0.381 -0.3683)
						)
						(arc
							(start 0.381 0.3683)
							(mid 0.321484 0.511984)
							(end 0.1778 0.5715)
						)
					)
					(width 0)
					(fill yes)
				)
			)
		)
		(pad "S" smd custom
			(at 0.98425 0.9525 270)
			(size 0.1905 0.1905)
			(layers "F.Cu" "F.Mask" "F.Paste")
			(net "GND")
			(options
				(clearance outline)
				(anchor circle)
			)
			(primitives
				(gr_poly
					(pts
						(arc
							(start -0.1778 0.5715)
							(mid -0.321484 0.511984)
							(end -0.381 0.3683)
						)
						(arc
							(start -0.381 -0.3683)
							(mid -0.321484 -0.511984)
							(end -0.1778 -0.5715)
						)
						(arc
							(start 0.1778 -0.5715)
							(mid 0.321484 -0.511984)
							(end 0.381 -0.3683)
						)
						(arc
							(start 0.381 0.3683)
							(mid 0.321484 0.511984)
							(end 0.1778 0.5715)
						)
					)
					(width 0)
					(fill yes)
				)
			)
		)
	)
	(footprint ""
		(layer "F.Cu")
		(at 81.407 -99.314)
		(property "Reference" "R405"
			(at 0 0 0)
			(layer "F.SilkS")
			(hide yes)
			(effects
				(font
					(size 1.27 1.27)
				)
			)
		)
		(property "Value" "91R3F-1-GP"
			(at -0.0254 -2.5146 0)
			(unlocked yes)
			(layer "F.Fab")
			(hide yes)
			(effects
				(font
					(size 1.016 1.016)
					(thickness 0.1524)
				)
			)
		)
		(property "Device Type" "R603H22"
			(at -0.0254 -4.0386 0)
			(unlocked yes)
			(layer "F.Fab")
			(hide yes)
			(effects
				(font
					(size 1.016 1.016)
					(thickness 0.1524)
				)
			)
		)
		(duplicate_pad_numbers_are_jumpers no)
		(fp_line
			(start -0.4826 0)
			(end -0.2032 0)
			(stroke
				(width 0.2032)
				(type default)
			)
			(layer "F.SilkS")
		)
		(fp_line
			(start 0.2032 0)
			(end 0.4826 0)
			(stroke
				(width 0.2032)
				(type default)
			)
			(layer "F.SilkS")
		)
		(fp_rect
			(start -0.5842 1.3335)
			(end 0.5842 -1.3335)
			(stroke
				(width 0)
				(type default)
			)
			(fill no)
			(layer "F.CrtYd")
		)
		(fp_rect
			(start -0.5842 1.3335)
			(end 0.5842 -1.3335)
			(stroke
				(width 0)
				(type default)
			)
			(fill no)
			(layer "F.Fab")
		)
		(pad "1" smd custom
			(at 0 -0.762)
			(size 0.2159 0.2159)
			(layers "F.Cu" "F.Mask" "F.Paste")
			(net "P5V_B_1")
			(options
				(clearance outline)
				(anchor circle)
			)
			(primitives
				(gr_poly
					(pts
						(arc
							(start -0.3302 -0.4318)
							(mid -0.402042 -0.402042)
							(end -0.4318 -0.3302)
						)
						(arc
							(start -0.4318 0.3302)
							(mid -0.402042 0.402042)
							(end -0.3302 0.4318)
						)
						(arc
							(start 0.3302 0.4318)
							(mid 0.402042 0.402042)
							(end 0.4318 0.3302)
						)
						(arc
							(start 0.4318 -0.3302)
							(mid 0.402042 -0.402042)
							(end 0.3302 -0.4318)
						)
					)
					(width 0)
					(fill yes)
				)
			)
		)
		(pad "2" smd custom
			(at 0 0.762)
			(size 0.2159 0.2159)
			(layers "F.Cu" "F.Mask" "F.Paste")
			(net "DRV_ACT_14")
			(options
				(clearance outline)
				(anchor circle)
			)
			(primitives
				(gr_poly
					(pts
						(arc
							(start -0.3302 -0.4318)
							(mid -0.402042 -0.402042)
							(end -0.4318 -0.3302)
						)
						(arc
							(start -0.4318 0.3302)
							(mid -0.402042 0.402042)
							(end -0.3302 0.4318)
						)
						(arc
							(start 0.3302 0.4318)
							(mid 0.402042 0.402042)
							(end 0.4318 0.3302)
						)
						(arc
							(start 0.4318 -0.3302)
							(mid 0.402042 -0.402042)
							(end 0.3302 -0.4318)
						)
					)
					(width 0)
					(fill yes)
				)
			)
		)
	)
	(footprint ""
		(layer "F.Cu")
		(at 476.4532 -250.571 180)
		(property "Reference" "R335"
			(at 0 0 180)
			(layer "F.SilkS")
			(hide yes)
			(effects
				(font
					(size 1.27 1.27)
				)
			)
		)
		(property "Value" "10KR2F-2-GP"
			(at 0.064008 -3.993896 180)
			(unlocked yes)
			(layer "F.Fab")
			(hide yes)
			(effects
				(font
					(size 1.016 1.016)
					(thickness 0.1524)
				)
			)
		)
		(property "Device Type" "R402H16"
			(at 0.064008 -5.517896 180)
			(unlocked yes)
			(layer "F.Fab")
			(hide yes)
			(effects
				(font
					(size 1.016 1.016)
					(thickness 0.1524)
				)
			)
		)
		(duplicate_pad_numbers_are_jumpers no)
		(fp_line
			(start 0.508 -0.9398)
			(end -0.508 -0.9398)
			(stroke
				(width 0.1524)
				(type default)
			)
			(layer "F.SilkS")
		)
		(fp_line
			(start -0.508 -0.9398)
			(end -0.508 0.9398)
			(stroke
				(width 0.1524)
				(type default)
			)
			(layer "F.SilkS")
		)
		(fp_rect
			(start -0.508 0.9398)
			(end 0.508 -0.9398)
			(stroke
				(width 0)
				(type default)
			)
			(fill no)
			(layer "F.CrtYd")
		)
		(fp_rect
			(start -0.508 0.9398)
			(end 0.508 -0.9398)
			(stroke
				(width 0)
				(type default)
			)
			(fill no)
			(layer "F.Fab")
		)
		(pad "1" smd custom
			(at 0 -0.4445 180)
			(size 0.1397 0.1397)
			(layers "F.Cu" "F.Mask" "F.Paste")
			(net "P3V3_STBY_B")
			(options
				(clearance outline)
				(anchor circle)
			)
			(primitives
				(gr_poly
					(pts
						(arc
							(start -0.1778 -0.2794)
							(mid -0.249642 -0.249642)
							(end -0.2794 -0.1778)
						)
						(arc
							(start -0.2794 0.1778)
							(mid -0.249642 0.249642)
							(end -0.1778 0.2794)
						)
						(arc
							(start 0.1778 0.2794)
							(mid 0.249642 0.249642)
							(end 0.2794 0.1778)
						)
						(arc
							(start 0.2794 -0.1778)
							(mid 0.249642 -0.249642)
							(end 0.1778 -0.2794)
						)
					)
					(width 0)
					(fill yes)
				)
			)
		)
		(pad "2" smd custom
			(at 0 0.4445 180)
			(size 0.1397 0.1397)
			(layers "F.Cu" "F.Mask" "F.Paste")
			(net "HDD_PRSNT_11")
			(options
				(clearance outline)
				(anchor circle)
			)
			(primitives
				(gr_poly
					(pts
						(arc
							(start -0.1778 -0.2794)
							(mid -0.249642 -0.249642)
							(end -0.2794 -0.1778)
						)
						(arc
							(start -0.2794 0.1778)
							(mid -0.249642 0.249642)
							(end -0.1778 0.2794)
						)
						(arc
							(start 0.1778 0.2794)
							(mid 0.249642 0.249642)
							(end 0.2794 0.1778)
						)
						(arc
							(start 0.2794 -0.1778)
							(mid 0.249642 -0.249642)
							(end 0.1778 -0.2794)
						)
					)
					(width 0)
					(fill yes)
				)
			)
		)
	)
	(footprint ""
		(layer "F.Cu")
		(at 248.270522 -360.349546 -90)
		(property "Reference" "R1041"
			(at 0 0 270)
			(layer "F.SilkS")
			(hide yes)
			(effects
				(font
					(size 1.27 1.27)
				)
			)
		)
		(property "Value" "100KR2F-L1-GP"
			(at 0.064008 -3.993896 270)
			(unlocked yes)
			(layer "F.Fab")
			(hide yes)
			(effects
				(font
					(size 1.016 1.016)
					(thickness 0.1524)
				)
			)
		)
		(property "Device Type" "R402H16"
			(at 0.064008 -5.517896 270)
			(unlocked yes)
			(layer "F.Fab")
			(hide yes)
			(effects
				(font
					(size 1.016 1.016)
					(thickness 0.1524)
				)
			)
		)
		(duplicate_pad_numbers_are_jumpers no)
		(fp_line
			(start -0.508 -0.9398)
			(end -0.508 0.9398)
			(stroke
				(width 0.1524)
				(type default)
			)
			(layer "F.SilkS")
		)
		(fp_line
			(start 0.508 -0.9398)
			(end -0.508 -0.9398)
			(stroke
				(width 0.1524)
				(type default)
			)
			(layer "F.SilkS")
		)
		(fp_rect
			(start -0.508 0.9398)
			(end 0.508 -0.9398)
			(stroke
				(width 0)
				(type default)
			)
			(fill no)
			(layer "F.CrtYd")
		)
		(fp_rect
			(start -0.508 0.9398)
			(end 0.508 -0.9398)
			(stroke
				(width 0)
				(type default)
			)
			(fill no)
			(layer "F.Fab")
		)
		(pad "1" smd custom
			(at 0 -0.4445 270)
			(size 0.1397 0.1397)
			(layers "F.Cu" "F.Mask" "F.Paste")
			(net "MB3_VCAP_R")
			(options
				(clearance outline)
				(anchor circle)
			)
			(primitives
				(gr_poly
					(pts
						(arc
							(start -0.1778 -0.2794)
							(mid -0.249642 -0.249642)
							(end -0.2794 -0.1778)
						)
						(arc
							(start -0.2794 0.1778)
							(mid -0.249642 0.249642)
							(end -0.1778 0.2794)
						)
						(arc
							(start 0.1778 0.2794)
							(mid 0.249642 0.249642)
							(end 0.2794 0.1778)
						)
						(arc
							(start 0.2794 -0.1778)
							(mid 0.249642 -0.249642)
							(end 0.1778 -0.2794)
						)
					)
					(width 0)
					(fill yes)
				)
			)
		)
		(pad "2" smd custom
			(at 0 0.4445 270)
			(size 0.1397 0.1397)
			(layers "F.Cu" "F.Mask" "F.Paste")
			(net "MB3_PSET_R")
			(options
				(clearance outline)
				(anchor circle)
			)
			(primitives
				(gr_poly
					(pts
						(arc
							(start -0.1778 -0.2794)
							(mid -0.249642 -0.249642)
							(end -0.2794 -0.1778)
						)
						(arc
							(start -0.2794 0.1778)
							(mid -0.249642 0.249642)
							(end -0.1778 0.2794)
						)
						(arc
							(start 0.1778 0.2794)
							(mid 0.249642 0.249642)
							(end 0.2794 0.1778)
						)
						(arc
							(start 0.2794 -0.1778)
							(mid 0.249642 -0.249642)
							(end 0.1778 -0.2794)
						)
					)
					(width 0)
					(fill yes)
				)
			)
		)
	)
	(footprint ""
		(layer "F.Cu")
		(at 211.95538 -238.48822 180)
		(property "Reference" "C8"
			(at 0 0 180)
			(layer "F.SilkS")
			(hide yes)
			(effects
				(font
					(size 1.27 1.27)
				)
			)
		)
		(property "Value" "SCD1U16V2KX-3GP"
			(at 1.1811 -2.7051 180)
			(unlocked yes)
			(layer "F.Fab")
			(hide yes)
			(effects
				(font
					(size 1.016 1.016)
					(thickness 0.1524)
				)
			)
		)
		(property "Device Type" "C402H22"
			(at 1.1811 -4.2291 180)
			(unlocked yes)
			(layer "F.Fab")
			(hide yes)
			(effects
				(font
					(size 1.016 1.016)
					(thickness 0.1524)
				)
			)
		)
		(duplicate_pad_numbers_are_jumpers no)
		(fp_rect
			(start -0.4318 0.9525)
			(end 0.4318 -0.9525)
			(stroke
				(width 0)
				(type default)
			)
			(fill no)
			(layer "F.CrtYd")
		)
		(fp_rect
			(start -0.4318 0.9525)
			(end 0.4318 -0.9525)
			(stroke
				(width 0)
				(type default)
			)
			(fill no)
			(layer "F.Fab")
		)
		(pad "1" smd custom
			(at 0 -0.4445 180)
			(size 0.1524 0.1524)
			(layers "F.Cu" "F.Mask" "F.Paste")
			(net "P3V3_STBY_B")
			(options
				(clearance outline)
				(anchor circle)
			)
			(primitives
				(gr_poly
					(pts
						(arc
							(start 0.3048 -0.2032)
							(mid 0.275042 -0.275042)
							(end 0.2032 -0.3048)
						)
						(arc
							(start -0.2032 -0.3048)
							(mid -0.275042 -0.275042)
							(end -0.3048 -0.2032)
						)
						(arc
							(start -0.3048 0.2032)
							(mid -0.275042 0.275042)
							(end -0.2032 0.3048)
						)
						(arc
							(start 0.2032 0.3048)
							(mid 0.275042 0.275042)
							(end 0.3048 0.2032)
						)
					)
					(width 0)
					(fill yes)
				)
			)
		)
		(pad "2" smd custom
			(at 0 0.4445 180)
			(size 0.1524 0.1524)
			(layers "F.Cu" "F.Mask" "F.Paste")
			(net "GND")
			(options
				(clearance outline)
				(anchor circle)
			)
			(primitives
				(gr_poly
					(pts
						(arc
							(start 0.3048 -0.2032)
							(mid 0.275042 -0.275042)
							(end 0.2032 -0.3048)
						)
						(arc
							(start -0.2032 -0.3048)
							(mid -0.275042 -0.275042)
							(end -0.3048 -0.2032)
						)
						(arc
							(start -0.3048 0.2032)
							(mid -0.275042 0.275042)
							(end -0.2032 0.3048)
						)
						(arc
							(start 0.2032 0.3048)
							(mid 0.275042 0.275042)
							(end 0.3048 0.2032)
						)
					)
					(width 0)
					(fill yes)
				)
			)
		)
	)
	(footprint ""
		(layer "F.Cu")
		(at 248.285 -309.118 90)
		(property "Reference" "R1091"
			(at 0 0 90)
			(layer "F.SilkS")
			(hide yes)
			(effects
				(font
					(size 1.27 1.27)
				)
			)
		)
		(property "Value" "0R2J-2-GP"
			(at 0.064008 -3.993896 90)
			(unlocked yes)
			(layer "F.Fab")
			(hide yes)
			(effects
				(font
					(size 1.016 1.016)
					(thickness 0.1524)
				)
			)
		)
		(property "Device Type" "R402H16"
			(at 0.064008 -5.517896 90)
			(unlocked yes)
			(layer "F.Fab")
			(hide yes)
			(effects
				(font
					(size 1.016 1.016)
					(thickness 0.1524)
				)
			)
		)
		(duplicate_pad_numbers_are_jumpers no)
		(fp_line
			(start 0.508 -0.9398)
			(end -0.508 -0.9398)
			(stroke
				(width 0.1524)
				(type default)
			)
			(layer "F.SilkS")
		)
		(fp_line
			(start -0.508 -0.9398)
			(end -0.508 0.9398)
			(stroke
				(width 0.1524)
				(type default)
			)
			(layer "F.SilkS")
		)
		(fp_rect
			(start -0.508 0.9398)
			(end 0.508 -0.9398)
			(stroke
				(width 0)
				(type default)
			)
			(fill no)
			(layer "F.CrtYd")
		)
		(fp_rect
			(start -0.508 0.9398)
			(end 0.508 -0.9398)
			(stroke
				(width 0)
				(type default)
			)
			(fill no)
			(layer "F.Fab")
		)
		(pad "1" smd custom
			(at 0 -0.4445 90)
			(size 0.1397 0.1397)
			(layers "F.Cu" "F.Mask" "F.Paste")
			(net "MAX31790_A_PWM_ST1")
			(options
				(clearance outline)
				(anchor circle)
			)
			(primitives
				(gr_poly
					(pts
						(arc
							(start -0.1778 -0.2794)
							(mid -0.249642 -0.249642)
							(end -0.2794 -0.1778)
						)
						(arc
							(start -0.2794 0.1778)
							(mid -0.249642 0.249642)
							(end -0.1778 0.2794)
						)
						(arc
							(start 0.1778 0.2794)
							(mid 0.249642 0.249642)
							(end 0.2794 0.1778)
						)
						(arc
							(start 0.2794 -0.1778)
							(mid 0.249642 -0.249642)
							(end 0.1778 -0.2794)
						)
					)
					(width 0)
					(fill yes)
				)
			)
		)
		(pad "2" smd custom
			(at 0 0.4445 90)
			(size 0.1397 0.1397)
			(layers "F.Cu" "F.Mask" "F.Paste")
			(net "GND")
			(options
				(clearance outline)
				(anchor circle)
			)
			(primitives
				(gr_poly
					(pts
						(arc
							(start -0.1778 -0.2794)
							(mid -0.249642 -0.249642)
							(end -0.2794 -0.1778)
						)
						(arc
							(start -0.2794 0.1778)
							(mid -0.249642 0.249642)
							(end -0.1778 0.2794)
						)
						(arc
							(start 0.1778 0.2794)
							(mid 0.249642 0.249642)
							(end 0.2794 0.1778)
						)
						(arc
							(start 0.2794 -0.1778)
							(mid 0.249642 -0.249642)
							(end 0.1778 -0.2794)
						)
					)
					(width 0)
					(fill yes)
				)
			)
		)
	)
)
